# TIMECARD (Time Appliance Project (Time Card)) — schematic netlist excerpt (pin names and nets, part order shuffled) for the footprints in the layout excerpt that follows; sources: Cadence DE-HDL packaged netlist, KiCad conversion of R4006-B0001-02_R01.brd

C45  CAPACITOR  1000PF 50V 5%  pkg SMC_0402R_H022  page 32 : \1\ = XP5R0V_SW ; \2\ = UNNAMED_516_CAPACITOR_I37_2
C172  CAPACITOR  100UF 6.3V 20%  pkg SMC_1210R_H110  page 14 : \1\ = XP3R3V_FPGA ; \2\ = SG

(kicad_pcb
	(version 20260206)
	(generator "pcbnew")
	(generator_version "10.0")
	(general
		(thickness 1.6)
		(legacy_teardrops no)
	)
	(paper "A4")
	(title_block
		(title "timecard-production-celestica-r4006 — R4006-B0001-02_R01.brd")
		(comment 1 "Time Appliance Project (Time Card) / footprints 909-910 of 1113")
	)
	(layers
		(0 "F.Cu" signal "TOP")
		(4 "In1.Cu" signal "L02_GND1")
		(6 "In2.Cu" signal "L03_SIG1")
		(8 "In3.Cu" signal "L04_GND2")
		(10 "In4.Cu" signal "L05_VCC1")
		(12 "In5.Cu" signal "L06_VCC2")
		(14 "In6.Cu" signal "L07_GND3")
		(16 "In7.Cu" signal "L08_SIG2")
		(18 "In8.Cu" signal "L09_GND4")
		(2 "B.Cu" signal "BOTTOM")
		(9 "F.Adhes" user "F.Adhesive")
		(11 "B.Adhes" user "B.Adhesive")
		(13 "F.Paste" user "Package Geometry/Pastemask Top")
		(15 "B.Paste" user "Package Geometry/Pastemask Bottom")
		(5 "F.SilkS" user "Ref Des/Silkscreen Top")
		(7 "B.SilkS" user "Ref Des/Silkscreen Bottom")
		(1 "F.Mask" user "Board Geometry/Soldermask Top")
		(3 "B.Mask" user "Board Geometry/Soldermask Bottom")
		(17 "Dwgs.User" user "User.Drawings")
		(19 "Cmts.User" user "User.Comments")
		(21 "Eco1.User" user "User.Eco1")
		(23 "Eco2.User" user "User.Eco2")
		(25 "Edge.Cuts" user "Board Geometry/Outline")
		(27 "Margin" user)
		(31 "F.CrtYd" user "Package Geometry/Place Bound Top")
		(29 "B.CrtYd" user "Package Geometry/Place Bound Bottom")
		(35 "F.Fab" user "Ref Des/Assembly Top")
		(33 "B.Fab" user "Ref Des/Assembly Bottom")
	)
	(footprint ""
		(layer "B.Cu")
		(at 102.489 -59.055)
		(property "Reference" "C172"
			(at -0.254 -2.11963 0)
			(unlocked yes)
			(layer "B.SilkS")
			(effects
				(font
					(size 0.7874 0.5842)
					(thickness 0.1524)
				)
				(justify mirror)
			)
		)
		(property "Value" "VAL*"
			(at -0.1016 3.769106 0)
			(unlocked yes)
			(layer "B.Fab")
			(hide yes)
			(effects
				(font
					(size 0.7874 0.5842)
					(thickness 0.1524)
				)
				(justify mirror)
			)
		)
		(property "Device Type" "CAPACITOR-G109-0G107-BM,100UF,A"
			(at -0.0762 2.829306 0)
			(unlocked yes)
			(layer "B.Fab")
			(hide yes)
			(effects
				(font
					(size 0.7874 0.5842)
					(thickness 0.1524)
				)
				(justify mirror)
			)
		)
		(property "User Part Number" "PARTNUM*"
			(at -0.2032 5.801106 0)
			(unlocked yes)
			(layer "Cmts.User")
			(hide yes)
			(effects
				(font
					(size 0.7874 0.5842)
					(thickness 0.1524)
				)
				(justify mirror)
			)
		)
		(property "Tolerance" "TOL*"
			(at -0.127 4.734306 0)
			(unlocked yes)
			(layer "Cmts.User")
			(hide yes)
			(effects
				(font
					(size 0.7874 0.5842)
					(thickness 0.1524)
				)
				(justify mirror)
			)
		)
		(duplicate_pad_numbers_are_jumpers no)
		(fp_line
			(start -2.159 -1.5748)
			(end -2.159 1.5748)
			(stroke
				(width 0.1)
				(type default)
			)
			(layer "B.SilkS")
		)
		(fp_line
			(start -2.159 1.5748)
			(end 2.159 1.5748)
			(stroke
				(width 0.1)
				(type default)
			)
			(layer "B.SilkS")
		)
		(fp_line
			(start 2.159 -1.5748)
			(end -2.159 -1.5748)
			(stroke
				(width 0.1)
				(type default)
			)
			(layer "B.SilkS")
		)
		(fp_line
			(start 2.159 1.5748)
			(end 2.159 -1.5748)
			(stroke
				(width 0.1)
				(type default)
			)
			(layer "B.SilkS")
		)
		(fp_rect
			(start 2.159 -1.5748)
			(end -2.159 1.5748)
			(stroke
				(width 0)
				(type default)
			)
			(fill no)
			(layer "B.CrtYd")
		)
		(fp_line
			(start -1.6002 -1.2446)
			(end 1.6002 -1.2446)
			(stroke
				(width 0.1)
				(type default)
			)
			(layer "B.Fab")
		)
		(fp_line
			(start -1.6002 1.2446)
			(end -1.6002 -1.2446)
			(stroke
				(width 0.1)
				(type default)
			)
			(layer "B.Fab")
		)
		(fp_line
			(start 1.6002 -1.2446)
			(end 1.6002 1.2446)
			(stroke
				(width 0.1)
				(type default)
			)
			(layer "B.Fab")
		)
		(fp_line
			(start 1.6002 1.2446)
			(end -1.6002 1.2446)
			(stroke
				(width 0.1)
				(type default)
			)
			(layer "B.Fab")
		)
		(pad "1" smd rect
			(at 1.3335 0 180)
			(size 1.143 2.6416)
			(layers "B.Cu" "B.Mask" "B.Paste")
			(net "XP3R3V_FPGA")
		)
		(pad "2" smd rect
			(at -1.3335 0 180)
			(size 1.143 2.6416)
			(layers "B.Cu" "B.Mask" "B.Paste")
			(net "SG")
		)
		(zone
			(layer "B.Cu")
			(hatch none 0.5)
			(connect_pads
				(clearance 0)
			)
			(min_thickness 0.25)
			(keepout
				(tracks allowed)
				(vias not_allowed)
				(pads allowed)
				(copperpour not_allowed)
				(footprints allowed)
			)
			(placement
				(enabled no)
				(sheetname "")
			)
			(fill
				(thermal_gap 0.5)
				(thermal_bridge_width 0.5)
				(island_removal_mode 0)
			)
			(polygon
				(pts
					(xy 103.1748 -60.452) (xy 101.8032 -60.452) (xy 101.8032 -57.658) (xy 103.1748 -57.658)
				)
			)
		)
	)
	(footprint ""
		(layer "B.Cu")
		(at 45.72 -102.743 -90)
		(property "Reference" "C45"
			(at 0.1524 -1.38303 270)
			(unlocked yes)
			(layer "B.SilkS")
			(effects
				(font
					(size 0.7874 0.5842)
					(thickness 0.1524)
				)
				(justify mirror)
			)
		)
		(property "Value" "VAL*"
			(at -0.0762 2.067306 270)
			(unlocked yes)
			(layer "B.Fab")
			(hide yes)
			(effects
				(font
					(size 0.7874 0.5842)
					(thickness 0.1524)
				)
				(justify mirror)
			)
		)
		(property "Tolerance" "TOL*"
			(at -0.0762 3.032506 270)
			(unlocked yes)
			(layer "Cmts.User")
			(hide yes)
			(effects
				(font
					(size 0.7874 0.5842)
					(thickness 0.1524)
				)
				(justify mirror)
			)
		)
		(property "User Part Number" "PARTNUM*"
			(at -0.1016 4.023106 270)
			(unlocked yes)
			(layer "Cmts.User")
			(hide yes)
			(effects
				(font
					(size 0.7874 0.5842)
					(thickness 0.1524)
				)
				(justify mirror)
			)
		)
		(property "Device Type" "CAPACITOR-G105-0A102-FJ,1000PFA"
			(at -0.0508 1.127506 270)
			(unlocked yes)
			(layer "B.Fab")
			(hide yes)
			(effects
				(font
					(size 0.7874 0.5842)
					(thickness 0.1524)
				)
				(justify mirror)
			)
		)
		(duplicate_pad_numbers_are_jumpers no)
		(fp_line
			(start -1.143 0.5588)
			(end -1.143 -0.5588)
			(stroke
				(width 0.1)
				(type default)
			)
			(layer "B.SilkS")
		)
		(fp_line
			(start 1.143 0.5588)
			(end -1.143 0.5588)
			(stroke
				(width 0.1)
				(type default)
			)
			(layer "B.SilkS")
		)
		(fp_line
			(start -1.143 -0.5588)
			(end 1.143 -0.5588)
			(stroke
				(width 0.1)
				(type default)
			)
			(layer "B.SilkS")
		)
		(fp_line
			(start 1.143 -0.5588)
			(end 1.143 0.5588)
			(stroke
				(width 0.1)
				(type default)
			)
			(layer "B.SilkS")
		)
		(fp_rect
			(start -1.143 -0.5588)
			(end 1.143 0.5588)
			(stroke
				(width 0)
				(type default)
			)
			(fill no)
			(layer "B.CrtYd")
		)
		(fp_line
			(start -0.508 0.3048)
			(end -0.508 -0.3048)
			(stroke
				(width 0.1)
				(type default)
			)
			(layer "B.Fab")
		)
		(fp_line
			(start 0.508 0.3048)
			(end -0.508 0.3048)
			(stroke
				(width 0.1)
				(type default)
			)
			(layer "B.Fab")
		)
		(fp_line
			(start -0.508 -0.3048)
			(end 0.508 -0.3048)
			(stroke
				(width 0.1)
				(type default)
			)
			(layer "B.Fab")
		)
		(fp_line
			(start 0.508 -0.3048)
			(end 0.508 0.3048)
			(stroke
				(width 0.1)
				(type default)
			)
			(layer "B.Fab")
		)
		(pad "1" smd rect
			(at 0.5334 0 90)
			(size 0.7112 0.6096)
			(layers "B.Cu" "B.Mask" "B.Paste")
			(net "XP5R0V_SW")
		)
		(pad "2" smd rect
			(at -0.5334 0 90)
			(size 0.7112 0.6096)
			(layers "B.Cu" "B.Mask" "B.Paste")
			(net "UNNAMED_516_CAPACITOR_I37_2")
		)
		(zone
			(layer "B.Cu")
			(hatch none 0.5)
			(connect_pads
				(clearance 0)
			)
			(min_thickness 0.25)
			(keepout
				(tracks allowed)
				(vias not_allowed)
				(pads allowed)
				(copperpour not_allowed)
				(footprints allowed)
			)
			(placement
				(enabled no)
				(sheetname "")
			)
			(fill
				(thermal_gap 0.5)
				(thermal_bridge_width 0.5)
				(island_removal_mode 0)
			)
			(polygon
				(pts
					(xy 46.0248 -102.8192) (xy 45.4152 -102.8192) (xy 45.4152 -102.6668) (xy 46.0248 -102.6668)
				)
			)
		)
	)
)
